(kicad_pcb
	(version 20260206)
	(generator "pcbnew")
	(generator_version "10.0")
	(general
		(thickness 1.6)
		(legacy_teardrops no)
	)
	(paper "A4")
	(title_block
		(title "03242023_DA0F0TMBIJ0_F0T_Motherboard_J_brd_V01_OCP.brd")
		(comment 1 "Grand Teton / footprints 1586-1591 of 6105")
	)
	(layers
		(0 "F.Cu" signal "TOP")
		(4 "In1.Cu" signal "GND")
		(6 "In2.Cu" signal "IN1")
		(8 "In3.Cu" signal "GND1")
		(10 "In4.Cu" signal "IN2")
		(12 "In5.Cu" signal "GND2")
		(14 "In6.Cu" signal "IN3")
		(16 "In7.Cu" signal "GND3")
		(18 "In8.Cu" signal "VCC")
		(20 "In9.Cu" signal "VCC1")
		(22 "In10.Cu" signal "GND4")
		(24 "In11.Cu" signal "IN4")
		(26 "In12.Cu" signal "GND5")
		(28 "In13.Cu" signal "IN5")
		(30 "In14.Cu" signal "GND6")
		(32 "In15.Cu" signal "IN6")
		(34 "In16.Cu" signal "GND7")
		(2 "B.Cu" signal "BOTTOM")
		(9 "F.Adhes" user "F.Adhesive")
		(11 "B.Adhes" user "B.Adhesive")
		(13 "F.Paste" user "Package Geometry/Pastemask Top")
		(15 "B.Paste" user "Package Geometry/Pastemask Bottom")
		(5 "F.SilkS" user "Ref Des/Silkscreen Top")
		(7 "B.SilkS" user "Ref Des/Silkscreen Bottom")
		(1 "F.Mask" user "Board Geometry/Soldermask Top")
		(3 "B.Mask" user "Board Geometry/Soldermask Bottom")
		(17 "Dwgs.User" user "User.Drawings")
		(19 "Cmts.User" user "User.Comments")
		(21 "Eco1.User" user "User.Eco1")
		(23 "Eco2.User" user "User.Eco2")
		(25 "Edge.Cuts" user "Board Geometry/Outline")
		(27 "Margin" user)
		(31 "F.CrtYd" user "Package Geometry/Place Bound Top")
		(29 "B.CrtYd" user "Package Geometry/Place Bound Bottom")
		(35 "F.Fab" user "Ref Des/Assembly Top")
		(33 "B.Fab" user "Ref Des/Assembly Bottom")
	)
	(footprint ""
		(layer "F.Cu")
		(at 85.39607 -343.496138 -90)
		(property "Reference" "PC484_P1_7"
			(at 0 0 270)
			(layer "F.SilkS")
			(hide yes)
			(effects
				(font
					(size 1.27 1.27)
				)
			)
		)
		(property "Value" ""
			(at 0 0 270)
			(layer "F.Fab")
			(effects
				(font
					(size 1.27 1.27)
				)
			)
		)
		(duplicate_pad_numbers_are_jumpers no)
		(fp_line
			(start -0.7874 0.4064)
			(end -0.7874 -0.4064)
			(stroke
				(width 0.1524)
				(type default)
			)
			(layer "F.SilkS")
		)
		(fp_line
			(start 0.7874 0.4064)
			(end -0.7874 0.4064)
			(stroke
				(width 0.1524)
				(type default)
			)
			(layer "F.SilkS")
		)
		(fp_line
			(start -0.7874 -0.4064)
			(end 0.7874 -0.4064)
			(stroke
				(width 0.1524)
				(type default)
			)
			(layer "F.SilkS")
		)
		(fp_line
			(start 0.7874 -0.4064)
			(end 0.7874 0.4064)
			(stroke
				(width 0.1524)
				(type default)
			)
			(layer "F.SilkS")
		)
		(fp_line
			(start -0.67945 0.3048)
			(end -0.67945 -0.305054)
			(stroke
				(width 0.1)
				(type default)
			)
			(layer "F.Fab")
		)
		(fp_line
			(start -0.12065 0.3048)
			(end -0.67945 0.3048)
			(stroke
				(width 0.1)
				(type default)
			)
			(layer "F.Fab")
		)
		(fp_line
			(start 0.120396 0.3048)
			(end 0.120396 0.2794)
			(stroke
				(width 0.1)
				(type default)
			)
			(layer "F.Fab")
		)
		(fp_line
			(start 0.67945 0.3048)
			(end 0.120396 0.3048)
			(stroke
				(width 0.1)
				(type default)
			)
			(layer "F.Fab")
		)
		(fp_line
			(start -0.12065 0.2794)
			(end -0.12065 0.3048)
			(stroke
				(width 0.1)
				(type default)
			)
			(layer "F.Fab")
		)
		(fp_line
			(start 0.120396 0.2794)
			(end -0.12065 0.2794)
			(stroke
				(width 0.1)
				(type default)
			)
			(layer "F.Fab")
		)
		(fp_line
			(start -0.12065 -0.2794)
			(end 0.12065 -0.2794)
			(stroke
				(width 0.1)
				(type default)
			)
			(layer "F.Fab")
		)
		(fp_line
			(start 0.12065 -0.2794)
			(end 0.12065 -0.3048)
			(stroke
				(width 0.1)
				(type default)
			)
			(layer "F.Fab")
		)
		(fp_line
			(start 0.12065 -0.3048)
			(end 0.67945 -0.3048)
			(stroke
				(width 0.1)
				(type default)
			)
			(layer "F.Fab")
		)
		(fp_line
			(start 0.67945 -0.3048)
			(end 0.67945 0.3048)
			(stroke
				(width 0.1)
				(type default)
			)
			(layer "F.Fab")
		)
		(fp_line
			(start -0.67945 -0.305054)
			(end -0.12065 -0.305054)
			(stroke
				(width 0.1)
				(type default)
			)
			(layer "F.Fab")
		)
		(fp_line
			(start -0.12065 -0.305054)
			(end -0.12065 -0.2794)
			(stroke
				(width 0.1)
				(type default)
			)
			(layer "F.Fab")
		)
		(pad "1" smd circle
			(at -0.40005 0 270)
			(size 0 0)
			(layers "F.Cu" "F.Mask" "F.Paste")
			(net "SW_P12V_PVCCIN_CPU1_FLT")
		)
		(pad "2" smd circle
			(at 0.40005 0 270)
			(size 0 0)
			(layers "F.Cu" "F.Mask" "F.Paste")
			(net "GND")
		)
	)
	(footprint ""
		(layer "F.Cu")
		(at 179.12588 -130.266948 90)
		(property "Reference" "R1417"
			(at 0 0 90)
			(layer "F.SilkS")
			(hide yes)
			(effects
				(font
					(size 1.27 1.27)
				)
			)
		)
		(property "Value" ""
			(at 0 0 90)
			(layer "F.Fab")
			(effects
				(font
					(size 1.27 1.27)
				)
			)
		)
		(duplicate_pad_numbers_are_jumpers no)
		(fp_line
			(start 0.7874 -0.4064)
			(end 0.7874 0.4064)
			(stroke
				(width 0.1524)
				(type default)
			)
			(layer "F.SilkS")
		)
		(fp_line
			(start -0.7874 -0.4064)
			(end 0.7874 -0.4064)
			(stroke
				(width 0.1524)
				(type default)
			)
			(layer "F.SilkS")
		)
		(fp_line
			(start 0.7874 0.4064)
			(end -0.7874 0.4064)
			(stroke
				(width 0.1524)
				(type default)
			)
			(layer "F.SilkS")
		)
		(fp_line
			(start -0.7874 0.4064)
			(end -0.7874 -0.4064)
			(stroke
				(width 0.1524)
				(type default)
			)
			(layer "F.SilkS")
		)
		(fp_line
			(start -0.12065 -0.305054)
			(end -0.12065 -0.2794)
			(stroke
				(width 0.1)
				(type default)
			)
			(layer "F.Fab")
		)
		(fp_line
			(start -0.67945 -0.305054)
			(end -0.12065 -0.305054)
			(stroke
				(width 0.1)
				(type default)
			)
			(layer "F.Fab")
		)
		(fp_line
			(start 0.67945 -0.3048)
			(end 0.67945 0.3048)
			(stroke
				(width 0.1)
				(type default)
			)
			(layer "F.Fab")
		)
		(fp_line
			(start 0.12065 -0.3048)
			(end 0.67945 -0.3048)
			(stroke
				(width 0.1)
				(type default)
			)
			(layer "F.Fab")
		)
		(fp_line
			(start 0.12065 -0.2794)
			(end 0.12065 -0.3048)
			(stroke
				(width 0.1)
				(type default)
			)
			(layer "F.Fab")
		)
		(fp_line
			(start -0.12065 -0.2794)
			(end 0.12065 -0.2794)
			(stroke
				(width 0.1)
				(type default)
			)
			(layer "F.Fab")
		)
		(fp_line
			(start 0.120396 0.2794)
			(end -0.12065 0.2794)
			(stroke
				(width 0.1)
				(type default)
			)
			(layer "F.Fab")
		)
		(fp_line
			(start -0.12065 0.2794)
			(end -0.12065 0.3048)
			(stroke
				(width 0.1)
				(type default)
			)
			(layer "F.Fab")
		)
		(fp_line
			(start 0.67945 0.3048)
			(end 0.120396 0.3048)
			(stroke
				(width 0.1)
				(type default)
			)
			(layer "F.Fab")
		)
		(fp_line
			(start 0.120396 0.3048)
			(end 0.120396 0.2794)
			(stroke
				(width 0.1)
				(type default)
			)
			(layer "F.Fab")
		)
		(fp_line
			(start -0.12065 0.3048)
			(end -0.67945 0.3048)
			(stroke
				(width 0.1)
				(type default)
			)
			(layer "F.Fab")
		)
		(fp_line
			(start -0.67945 0.3048)
			(end -0.67945 -0.305054)
			(stroke
				(width 0.1)
				(type default)
			)
			(layer "F.Fab")
		)
		(pad "1" smd circle
			(at -0.40005 0 90)
			(size 0 0)
			(layers "F.Cu" "F.Mask" "F.Paste")
			(net "RST_PCIE_CPU0_DEV_PERST_N")
		)
		(pad "2" smd circle
			(at 0.40005 0 90)
			(size 0 0)
			(layers "F.Cu" "F.Mask" "F.Paste")
			(net "GND")
		)
	)
	(footprint ""
		(layer "F.Cu")
		(at 50.317654 -153.644854)
		(property "Reference" "PC1364"
			(at 0 0 0)
			(layer "F.SilkS")
			(hide yes)
			(effects
				(font
					(size 1.27 1.27)
				)
			)
		)
		(property "Value" ""
			(at 0 0 0)
			(layer "F.Fab")
			(effects
				(font
					(size 1.27 1.27)
				)
			)
		)
		(duplicate_pad_numbers_are_jumpers no)
		(fp_line
			(start -0.7874 -0.4064)
			(end 0.7874 -0.4064)
			(stroke
				(width 0.1524)
				(type default)
			)
			(layer "F.SilkS")
		)
		(fp_line
			(start -0.7874 0.4064)
			(end -0.7874 -0.4064)
			(stroke
				(width 0.1524)
				(type default)
			)
			(layer "F.SilkS")
		)
		(fp_line
			(start 0.7874 -0.4064)
			(end 0.7874 0.4064)
			(stroke
				(width 0.1524)
				(type default)
			)
			(layer "F.SilkS")
		)
		(fp_line
			(start 0.7874 0.4064)
			(end -0.7874 0.4064)
			(stroke
				(width 0.1524)
				(type default)
			)
			(layer "F.SilkS")
		)
		(fp_line
			(start -0.67945 -0.305054)
			(end -0.12065 -0.305054)
			(stroke
				(width 0.1)
				(type default)
			)
			(layer "F.Fab")
		)
		(fp_line
			(start -0.67945 0.3048)
			(end -0.67945 -0.305054)
			(stroke
				(width 0.1)
				(type default)
			)
			(layer "F.Fab")
		)
		(fp_line
			(start -0.12065 -0.305054)
			(end -0.12065 -0.2794)
			(stroke
				(width 0.1)
				(type default)
			)
			(layer "F.Fab")
		)
		(fp_line
			(start -0.12065 -0.2794)
			(end 0.12065 -0.2794)
			(stroke
				(width 0.1)
				(type default)
			)
			(layer "F.Fab")
		)
		(fp_line
			(start -0.12065 0.2794)
			(end -0.12065 0.3048)
			(stroke
				(width 0.1)
				(type default)
			)
			(layer "F.Fab")
		)
		(fp_line
			(start -0.12065 0.3048)
			(end -0.67945 0.3048)
			(stroke
				(width 0.1)
				(type default)
			)
			(layer "F.Fab")
		)
		(fp_line
			(start 0.120396 0.2794)
			(end -0.12065 0.2794)
			(stroke
				(width 0.1)
				(type default)
			)
			(layer "F.Fab")
		)
		(fp_line
			(start 0.120396 0.3048)
			(end 0.120396 0.2794)
			(stroke
				(width 0.1)
				(type default)
			)
			(layer "F.Fab")
		)
		(fp_line
			(start 0.12065 -0.3048)
			(end 0.67945 -0.3048)
			(stroke
				(width 0.1)
				(type default)
			)
			(layer "F.Fab")
		)
		(fp_line
			(start 0.12065 -0.2794)
			(end 0.12065 -0.3048)
			(stroke
				(width 0.1)
				(type default)
			)
			(layer "F.Fab")
		)
		(fp_line
			(start 0.67945 -0.3048)
			(end 0.67945 0.3048)
			(stroke
				(width 0.1)
				(type default)
			)
			(layer "F.Fab")
		)
		(fp_line
			(start 0.67945 0.3048)
			(end 0.120396 0.3048)
			(stroke
				(width 0.1)
				(type default)
			)
			(layer "F.Fab")
		)
		(pad "1" smd circle
			(at -0.40005 0)
			(size 0 0)
			(layers "F.Cu" "F.Mask" "F.Paste")
			(net "GND")
		)
		(pad "2" smd circle
			(at 0.40005 0)
			(size 0 0)
			(layers "F.Cu" "F.Mask" "F.Paste")
			(net "PVCCINFAON_CPU1_VREF")
		)
	)
	(footprint ""
		(layer "F.Cu")
		(at 210.3882 -107.4166 -90)
		(property "Reference" "R4783"
			(at 0 0 270)
			(layer "F.SilkS")
			(hide yes)
			(effects
				(font
					(size 1.27 1.27)
				)
			)
		)
		(property "Value" ""
			(at 0 0 270)
			(layer "F.Fab")
			(effects
				(font
					(size 1.27 1.27)
				)
			)
		)
		(duplicate_pad_numbers_are_jumpers no)
		(fp_line
			(start -0.7874 0.4064)
			(end -0.7874 -0.4064)
			(stroke
				(width 0.1524)
				(type default)
			)
			(layer "F.SilkS")
		)
		(fp_line
			(start 0.7874 0.4064)
			(end -0.7874 0.4064)
			(stroke
				(width 0.1524)
				(type default)
			)
			(layer "F.SilkS")
		)
		(fp_line
			(start -0.7874 -0.4064)
			(end 0.7874 -0.4064)
			(stroke
				(width 0.1524)
				(type default)
			)
			(layer "F.SilkS")
		)
		(fp_line
			(start 0.7874 -0.4064)
			(end 0.7874 0.4064)
			(stroke
				(width 0.1524)
				(type default)
			)
			(layer "F.SilkS")
		)
		(fp_line
			(start -0.67945 0.3048)
			(end -0.67945 -0.305054)
			(stroke
				(width 0.1)
				(type default)
			)
			(layer "F.Fab")
		)
		(fp_line
			(start -0.12065 0.3048)
			(end -0.67945 0.3048)
			(stroke
				(width 0.1)
				(type default)
			)
			(layer "F.Fab")
		)
		(fp_line
			(start 0.120396 0.3048)
			(end 0.120396 0.2794)
			(stroke
				(width 0.1)
				(type default)
			)
			(layer "F.Fab")
		)
		(fp_line
			(start 0.67945 0.3048)
			(end 0.120396 0.3048)
			(stroke
				(width 0.1)
				(type default)
			)
			(layer "F.Fab")
		)
		(fp_line
			(start -0.12065 0.2794)
			(end -0.12065 0.3048)
			(stroke
				(width 0.1)
				(type default)
			)
			(layer "F.Fab")
		)
		(fp_line
			(start 0.120396 0.2794)
			(end -0.12065 0.2794)
			(stroke
				(width 0.1)
				(type default)
			)
			(layer "F.Fab")
		)
		(fp_line
			(start -0.12065 -0.2794)
			(end 0.12065 -0.2794)
			(stroke
				(width 0.1)
				(type default)
			)
			(layer "F.Fab")
		)
		(fp_line
			(start 0.12065 -0.2794)
			(end 0.12065 -0.3048)
			(stroke
				(width 0.1)
				(type default)
			)
			(layer "F.Fab")
		)
		(fp_line
			(start 0.12065 -0.3048)
			(end 0.67945 -0.3048)
			(stroke
				(width 0.1)
				(type default)
			)
			(layer "F.Fab")
		)
		(fp_line
			(start 0.67945 -0.3048)
			(end 0.67945 0.3048)
			(stroke
				(width 0.1)
				(type default)
			)
			(layer "F.Fab")
		)
		(fp_line
			(start -0.67945 -0.305054)
			(end -0.12065 -0.305054)
			(stroke
				(width 0.1)
				(type default)
			)
			(layer "F.Fab")
		)
		(fp_line
			(start -0.12065 -0.305054)
			(end -0.12065 -0.2794)
			(stroke
				(width 0.1)
				(type default)
			)
			(layer "F.Fab")
		)
		(pad "1" smd circle
			(at -0.40005 0 270)
			(size 0 0)
			(layers "F.Cu" "F.Mask" "F.Paste")
			(net "IRQ_UV_DETECT_R2_N")
		)
		(pad "2" smd circle
			(at 0.40005 0 270)
			(size 0 0)
			(layers "F.Cu" "F.Mask" "F.Paste")
			(net "IRQ_UV_DETECT_N")
		)
	)
	(footprint ""
		(layer "F.Cu")
		(at 373.476774 -335.176368)
		(property "Reference" "PC274_P0_4"
			(at 0 0 0)
			(layer "F.SilkS")
			(hide yes)
			(effects
				(font
					(size 1.27 1.27)
				)
			)
		)
		(property "Value" ""
			(at 0 0 0)
			(layer "F.Fab")
			(effects
				(font
					(size 1.27 1.27)
				)
			)
		)
		(duplicate_pad_numbers_are_jumpers no)
		(fp_line
			(start -0.7874 -0.4064)
			(end 0.7874 -0.4064)
			(stroke
				(width 0.1524)
				(type default)
			)
			(layer "F.SilkS")
		)
		(fp_line
			(start -0.7874 0.4064)
			(end -0.7874 -0.4064)
			(stroke
				(width 0.1524)
				(type default)
			)
			(layer "F.SilkS")
		)
		(fp_line
			(start 0.7874 -0.4064)
			(end 0.7874 0.4064)
			(stroke
				(width 0.1524)
				(type default)
			)
			(layer "F.SilkS")
		)
		(fp_line
			(start 0.7874 0.4064)
			(end -0.7874 0.4064)
			(stroke
				(width 0.1524)
				(type default)
			)
			(layer "F.SilkS")
		)
		(fp_line
			(start -0.67945 -0.305054)
			(end -0.12065 -0.305054)
			(stroke
				(width 0.1)
				(type default)
			)
			(layer "F.Fab")
		)
		(fp_line
			(start -0.67945 0.3048)
			(end -0.67945 -0.305054)
			(stroke
				(width 0.1)
				(type default)
			)
			(layer "F.Fab")
		)
		(fp_line
			(start -0.12065 -0.305054)
			(end -0.12065 -0.2794)
			(stroke
				(width 0.1)
				(type default)
			)
			(layer "F.Fab")
		)
		(fp_line
			(start -0.12065 -0.2794)
			(end 0.12065 -0.2794)
			(stroke
				(width 0.1)
				(type default)
			)
			(layer "F.Fab")
		)
		(fp_line
			(start -0.12065 0.2794)
			(end -0.12065 0.3048)
			(stroke
				(width 0.1)
				(type default)
			)
			(layer "F.Fab")
		)
		(fp_line
			(start -0.12065 0.3048)
			(end -0.67945 0.3048)
			(stroke
				(width 0.1)
				(type default)
			)
			(layer "F.Fab")
		)
		(fp_line
			(start 0.120396 0.2794)
			(end -0.12065 0.2794)
			(stroke
				(width 0.1)
				(type default)
			)
			(layer "F.Fab")
		)
		(fp_line
			(start 0.120396 0.3048)
			(end 0.120396 0.2794)
			(stroke
				(width 0.1)
				(type default)
			)
			(layer "F.Fab")
		)
		(fp_line
			(start 0.12065 -0.3048)
			(end 0.67945 -0.3048)
			(stroke
				(width 0.1)
				(type default)
			)
			(layer "F.Fab")
		)
		(fp_line
			(start 0.12065 -0.2794)
			(end 0.12065 -0.3048)
			(stroke
				(width 0.1)
				(type default)
			)
			(layer "F.Fab")
		)
		(fp_line
			(start 0.67945 -0.3048)
			(end 0.67945 0.3048)
			(stroke
				(width 0.1)
				(type default)
			)
			(layer "F.Fab")
		)
		(fp_line
			(start 0.67945 0.3048)
			(end 0.120396 0.3048)
			(stroke
				(width 0.1)
				(type default)
			)
			(layer "F.Fab")
		)
		(pad "1" smd circle
			(at -0.40005 0)
			(size 0 0)
			(layers "F.Cu" "F.Mask" "F.Paste")
			(net "SW_P12V_PVCCIN_CPU0_FLT")
		)
		(pad "2" smd circle
			(at 0.40005 0)
			(size 0 0)
			(layers "F.Cu" "F.Mask" "F.Paste")
			(net "GND")
		)
	)
	(footprint ""
		(layer "F.Cu")
		(at 164.592 -103.342948)
		(property "Reference" "R1755"
			(at 0 0 0)
			(layer "F.SilkS")
			(hide yes)
			(effects
				(font
					(size 1.27 1.27)
				)
			)
		)
		(property "Value" ""
			(at 0 0 0)
			(layer "F.Fab")
			(effects
				(font
					(size 1.27 1.27)
				)
			)
		)
		(duplicate_pad_numbers_are_jumpers no)
		(fp_line
			(start -0.7874 -0.4064)
			(end 0.7874 -0.4064)
			(stroke
				(width 0.1524)
				(type default)
			)
			(layer "F.SilkS")
		)
		(fp_line
			(start -0.7874 0.4064)
			(end -0.7874 -0.4064)
			(stroke
				(width 0.1524)
				(type default)
			)
			(layer "F.SilkS")
		)
		(fp_line
			(start 0.7874 -0.4064)
			(end 0.7874 0.4064)
			(stroke
				(width 0.1524)
				(type default)
			)
			(layer "F.SilkS")
		)
		(fp_line
			(start 0.7874 0.4064)
			(end -0.7874 0.4064)
			(stroke
				(width 0.1524)
				(type default)
			)
			(layer "F.SilkS")
		)
		(fp_line
			(start -0.67945 -0.305054)
			(end -0.12065 -0.305054)
			(stroke
				(width 0.1)
				(type default)
			)
			(layer "F.Fab")
		)
		(fp_line
			(start -0.67945 0.3048)
			(end -0.67945 -0.305054)
			(stroke
				(width 0.1)
				(type default)
			)
			(layer "F.Fab")
		)
		(fp_line
			(start -0.12065 -0.305054)
			(end -0.12065 -0.2794)
			(stroke
				(width 0.1)
				(type default)
			)
			(layer "F.Fab")
		)
		(fp_line
			(start -0.12065 -0.2794)
			(end 0.12065 -0.2794)
			(stroke
				(width 0.1)
				(type default)
			)
			(layer "F.Fab")
		)
		(fp_line
			(start -0.12065 0.2794)
			(end -0.12065 0.3048)
			(stroke
				(width 0.1)
				(type default)
			)
			(layer "F.Fab")
		)
		(fp_line
			(start -0.12065 0.3048)
			(end -0.67945 0.3048)
			(stroke
				(width 0.1)
				(type default)
			)
			(layer "F.Fab")
		)
		(fp_line
			(start 0.120396 0.2794)
			(end -0.12065 0.2794)
			(stroke
				(width 0.1)
				(type default)
			)
			(layer "F.Fab")
		)
		(fp_line
			(start 0.120396 0.3048)
			(end 0.120396 0.2794)
			(stroke
				(width 0.1)
				(type default)
			)
			(layer "F.Fab")
		)
		(fp_line
			(start 0.12065 -0.3048)
			(end 0.67945 -0.3048)
			(stroke
				(width 0.1)
				(type default)
			)
			(layer "F.Fab")
		)
		(fp_line
			(start 0.12065 -0.2794)
			(end 0.12065 -0.3048)
			(stroke
				(width 0.1)
				(type default)
			)
			(layer "F.Fab")
		)
		(fp_line
			(start 0.67945 -0.3048)
			(end 0.67945 0.3048)
			(stroke
				(width 0.1)
				(type default)
			)
			(layer "F.Fab")
		)
		(fp_line
			(start 0.67945 0.3048)
			(end 0.120396 0.3048)
			(stroke
				(width 0.1)
				(type default)
			)
			(layer "F.Fab")
		)
		(pad "1" smd circle
			(at -0.40005 0)
			(size 0 0)
			(layers "F.Cu" "F.Mask" "F.Paste")
			(net "SGPIO_DO_1")
		)
		(pad "2" smd circle
			(at 0.40005 0)
			(size 0 0)
			(layers "F.Cu" "F.Mask" "F.Paste")
			(net "SGPIO_BMC_DOUT")
		)
	)
)
